(kicad_pcb
	(version 20241229)
	(generator "pcbnew")
	(generator_version "9.0")
	(general
		(thickness 1.6296)
		(legacy_teardrops no)
	)
	(paper "A3")
	(title_block
		(title "Thunderbolt to 10GbE adapter")
		(date "2026-04-21")
		(rev "1.1.0")
		(company "Antmicro Ltd")
		(comment 1 "www.antmicro.com")
		(comment 9 "footprints 218-223 of 703")
	)
	(layers
		(0 "F.Cu" signal)
		(4 "In1.Cu" signal)
		(6 "In2.Cu" signal)
		(8 "In3.Cu" signal)
		(10 "In4.Cu" signal)
		(12 "In5.Cu" signal)
		(14 "In6.Cu" signal)
		(2 "B.Cu" signal)
		(9 "F.Adhes" user "F.Adhesive")
		(11 "B.Adhes" user "B.Adhesive")
		(13 "F.Paste" user)
		(15 "B.Paste" user)
		(5 "F.SilkS" user "F.Silkscreen")
		(7 "B.SilkS" user "B.Silkscreen")
		(1 "F.Mask" user)
		(3 "B.Mask" user)
		(17 "Dwgs.User" user "User.Drawings")
		(19 "Cmts.User" user "User.Comments")
		(21 "Eco1.User" user "User.Eco1")
		(23 "Eco2.User" user "User.Eco2")
		(25 "Edge.Cuts" user)
		(27 "Margin" user)
		(31 "F.CrtYd" user "F.Courtyard")
		(29 "B.CrtYd" user "B.Courtyard")
		(35 "F.Fab" user)
		(33 "B.Fab" user)
	)
	(footprint "antmicro-footprints:MP_Pad6mm_Drill3.2mm"
		(layer "F.Cu")
		(at 180 124)
		(property "Reference" "MP2"
			(at 1 -3.25 0)
			(layer "F.SilkS")
			(effects
				(font
					(size 0.7 0.7)
					(thickness 0.15)
				)
				(justify left bottom)
			)
		)
		(property "Value" "MP_Pad6mm_Drill3.2mm"
			(at 0 3.9 0)
			(layer "F.Fab")
			(effects
				(font
					(size 0.7 0.7)
					(thickness 0.15)
				)
				(justify left bottom)
			)
		)
		(property "Description" "Mechanical part"
			(at 0 0 0)
			(layer "F.Fab")
			(hide yes)
			(effects
				(font
					(size 1.27 1.27)
					(thickness 0.15)
				)
			)
		)
		(property "Author" "Antmicro"
			(at 0 0 0)
			(unlocked yes)
			(layer "F.Fab")
			(hide yes)
			(effects
				(font
					(size 1 1)
					(thickness 0.15)
				)
			)
		)
		(property "License" "Apache-2.0"
			(at 0 0 0)
			(unlocked yes)
			(layer "F.Fab")
			(hide yes)
			(effects
				(font
					(size 1 1)
					(thickness 0.15)
				)
			)
		)
		(sheetname "/")
		(sheetfile "thunderbolt-to-10gbe-adapter.kicad_sch")
		(attr exclude_from_pos_files exclude_from_bom)
		(fp_circle
			(center 0 0)
			(end 3.25 0)
			(stroke
				(width 0.05)
				(type default)
			)
			(fill no)
			(layer "F.CrtYd")
		)
		(fp_text user "${REFERENCE}"
			(at -0.178 6.025 0)
			(layer "F.Fab")
			(effects
				(font
					(size 0.7 0.7)
					(thickness 0.15)
				)
				(justify left bottom)
			)
		)
		(fp_text user "License: Apache-2.0"
			(at -0.178 8.425 0)
			(layer "F.Fab")
			(effects
				(font
					(size 0.7 0.7)
					(thickness 0.15)
				)
				(justify left bottom)
			)
		)
		(fp_text user "Author: Antmicro"
			(at -0.178 7.225 0)
			(layer "F.Fab")
			(effects
				(font
					(size 0.7 0.7)
					(thickness 0.15)
				)
				(justify left bottom)
			)
		)
		(pad "1" thru_hole circle
			(at 0 0)
			(size 6 6)
			(drill 3.2)
			(layers "*.Cu" "*.Mask")
			(remove_unused_layers no)
			(net 23 "GND")
			(pintype "passive")
		)
	)
	(footprint "antmicro-footprints:R_0402_1005Metric"
		(layer "F.Cu")
		(at 147.2 116.4 -90)
		(descr "Resistor SMD 0402")
		(tags "resistor SMD 0402")
		(property "Reference" "R81"
			(at 0 -1 270)
			(layer "F.SilkS")
			(effects
				(font
					(size 0.7 0.7)
					(thickness 0.15)
				)
			)
		)
		(property "Value" "R_3k3_0402"
			(at -1.011843 1.772047 270)
			(layer "F.Fab")
			(effects
				(font
					(size 0.7 0.7)
					(thickness 0.15)
				)
				(justify left bottom)
			)
		)
		(property "Datasheet" "https://www.bourns.com/docs/product-datasheets/cr.pdf"
			(at 0 0 270)
			(layer "F.Fab")
			(hide yes)
			(effects
				(font
					(size 1.27 1.27)
					(thickness 0.15)
				)
			)
		)
		(property "Description" "SMD Chip Resistor, 3.3 kohm, ± 1%, 63 mW, 0402 [1005 Metric], Thick Film, General Purpose"
			(at 0 0 270)
			(layer "F.Fab")
			(hide yes)
			(effects
				(font
					(size 1.27 1.27)
					(thickness 0.15)
				)
			)
		)
		(property "MPN" "CR0402-FX-3301GLF"
			(at 0 0 270)
			(unlocked yes)
			(layer "F.Fab")
			(hide yes)
			(effects
				(font
					(size 1 1)
					(thickness 0.15)
				)
			)
		)
		(property "Manufacturer" "Bourns"
			(at 0 0 270)
			(unlocked yes)
			(layer "F.Fab")
			(hide yes)
			(effects
				(font
					(size 1 1)
					(thickness 0.15)
				)
			)
		)
		(property "License" "Apache-2.0"
			(at 0 0 270)
			(unlocked yes)
			(layer "F.Fab")
			(hide yes)
			(effects
				(font
					(size 1 1)
					(thickness 0.15)
				)
			)
		)
		(property "Val" "3k3"
			(at 0 0 270)
			(unlocked yes)
			(layer "F.Fab")
			(hide yes)
			(effects
				(font
					(size 1 1)
					(thickness 0.15)
				)
			)
		)
		(property "Tolerance" "1%"
			(at 0 0 270)
			(unlocked yes)
			(layer "F.Fab")
			(hide yes)
			(effects
				(font
					(size 1 1)
					(thickness 0.15)
				)
			)
		)
		(property "Author" "Antmicro"
			(at 0 0 270)
			(unlocked yes)
			(layer "F.Fab")
			(hide yes)
			(effects
				(font
					(size 1 1)
					(thickness 0.15)
				)
			)
		)
		(sheetname "/TB flash memory/")
		(sheetfile "flash-memory.kicad_sch")
		(attr smd)
		(fp_rect
			(start -0.925 -0.47)
			(end 0.925 0.47)
			(stroke
				(width 0.05)
				(type default)
			)
			(fill no)
			(layer "F.CrtYd")
		)
		(fp_rect
			(start -0.5 -0.25)
			(end 0.5 0.25)
			(stroke
				(width 0.15)
				(type solid)
			)
			(fill no)
			(layer "F.Fab")
		)
		(fp_text user "License: Apache-2.0"
			(at -0.95 5.169 270)
			(layer "F.Fab")
			(effects
				(font
					(size 0.7 0.7)
					(thickness 0.15)
				)
				(justify left bottom)
			)
		)
		(fp_text user "${REFERENCE}"
			(at -0.95 3.168 270)
			(layer "F.Fab")
			(effects
				(font
					(size 0.7 0.7)
					(thickness 0.15)
				)
				(justify left bottom)
			)
		)
		(fp_text user "Author: Antmicro"
			(at -0.95 4.169 270)
			(layer "F.Fab")
			(effects
				(font
					(size 0.7 0.7)
					(thickness 0.15)
				)
				(justify left bottom)
			)
		)
		(pad "1" smd roundrect
			(at -0.48 0 270)
			(size 0.59 0.64)
			(layers "F.Cu" "F.Mask" "F.Paste")
			(roundrect_rratio 0.25)
			(net 57 "+3V3_TB")
			(pintype "passive")
		)
		(pad "2" smd roundrect
			(at 0.48 0 270)
			(size 0.59 0.64)
			(layers "F.Cu" "F.Mask" "F.Paste")
			(roundrect_rratio 0.25)
			(net 370 "/TB flash memory/FLASH_HOLD")
			(pintype "passive")
		)
	)
	(footprint "antmicro-footprints:C_0402_1005Metric"
		(layer "F.Cu")
		(at 161.4 51.5 -90)
		(descr "Capacitor SMD 0402")
		(tags "capacitor SMD 0402")
		(property "Reference" "C316"
			(at 1.65 -1.8 270)
			(layer "F.SilkS")
			(effects
				(font
					(size 0.7 0.7)
					(thickness 0.15)
				)
				(justify left bottom)
			)
		)
		(property "Value" "C_4u7_25V_0402"
			(at -1.022927 2.155213 270)
			(layer "F.Fab")
			(effects
				(font
					(size 0.7 0.7)
					(thickness 0.15)
				)
				(justify left bottom)
			)
		)
		(property "Datasheet" "https://www.murata.com/products/productdetail?partno=GRM155C61E475ME15%23"
			(at 0 0 270)
			(layer "F.Fab")
			(hide yes)
			(effects
				(font
					(size 1.27 1.27)
					(thickness 0.15)
				)
			)
		)
		(property "Description" "SMD Multilayer Ceramic Capacitor"
			(at 0 0 270)
			(layer "F.Fab")
			(hide yes)
			(effects
				(font
					(size 1.27 1.27)
					(thickness 0.15)
				)
			)
		)
		(property "MPN" "GRM155C61E475ME15J"
			(at 0 0 270)
			(unlocked yes)
			(layer "F.Fab")
			(hide yes)
			(effects
				(font
					(size 1 1)
					(thickness 0.15)
				)
			)
		)
		(property "Manufacturer" "Murata"
			(at 0 0 270)
			(unlocked yes)
			(layer "F.Fab")
			(hide yes)
			(effects
				(font
					(size 1 1)
					(thickness 0.15)
				)
			)
		)
		(property "License" "Apache-2.0"
			(at 0 0 270)
			(unlocked yes)
			(layer "F.Fab")
			(hide yes)
			(effects
				(font
					(size 1 1)
					(thickness 0.15)
				)
			)
		)
		(property "Author" "Antmicro"
			(at 0 0 270)
			(unlocked yes)
			(layer "F.Fab")
			(hide yes)
			(effects
				(font
					(size 1 1)
					(thickness 0.15)
				)
			)
		)
		(property "Val" "4u7"
			(at 0 0 270)
			(unlocked yes)
			(layer "F.Fab")
			(hide yes)
			(effects
				(font
					(size 1 1)
					(thickness 0.15)
				)
			)
		)
		(property "Voltage" "25V"
			(at 0 0 270)
			(unlocked yes)
			(layer "F.Fab")
			(hide yes)
			(effects
				(font
					(size 1 1)
					(thickness 0.15)
				)
			)
		)
		(property "Dielectric" "X5S"
			(at 0 0 270)
			(unlocked yes)
			(layer "F.Fab")
			(hide yes)
			(effects
				(font
					(size 1 1)
					(thickness 0.15)
				)
			)
		)
		(sheetname "/Power input/")
		(sheetfile "power_input.kicad_sch")
		(attr smd)
		(fp_rect
			(start -0.925 -0.47)
			(end 0.925 0.47)
			(stroke
				(width 0.05)
				(type default)
			)
			(fill no)
			(layer "F.CrtYd")
		)
		(fp_line
			(start -0.494 0.248)
			(end -0.494 -0.25)
			(stroke
				(width 0.15)
				(type solid)
			)
			(layer "F.Fab")
		)
		(fp_line
			(start 0.504 0.248)
			(end -0.494 0.248)
			(stroke
				(width 0.15)
				(type solid)
			)
			(layer "F.Fab")
		)
		(fp_line
			(start -0.494 -0.25)
			(end 0.504 -0.25)
			(stroke
				(width 0.15)
				(type solid)
			)
			(layer "F.Fab")
		)
		(fp_line
			(start 0.504 -0.25)
			(end 0.504 0.248)
			(stroke
				(width 0.15)
				(type solid)
			)
			(layer "F.Fab")
		)
		(fp_text user "License: Apache-2.0"
			(at -0.939 5.799 270)
			(layer "F.Fab")
			(effects
				(font
					(size 0.7 0.7)
					(thickness 0.15)
				)
				(justify left bottom)
			)
		)
		(fp_text user "${REFERENCE}"
			(at -0.939 4.599 270)
			(layer "F.Fab")
			(effects
				(font
					(size 0.7 0.7)
					(thickness 0.15)
				)
				(justify left bottom)
			)
		)
		(fp_text user "Author: Antmicro"
			(at -0.939 3.399 270)
			(layer "F.Fab")
			(effects
				(font
					(size 0.7 0.7)
					(thickness 0.15)
				)
				(justify left bottom)
			)
		)
		(pad "1" smd roundrect
			(at -0.48 0 270)
			(size 0.59 0.64)
			(layers "F.Cu" "F.Mask" "F.Paste")
			(roundrect_rratio 0.25)
			(net 23 "GND")
			(pintype "passive")
		)
		(pad "2" smd roundrect
			(at 0.48 0 270)
			(size 0.59 0.64)
			(layers "F.Cu" "F.Mask" "F.Paste")
			(roundrect_rratio 0.25)
			(net 346 "/Power input/5V_VDRV")
			(pintype "passive")
		)
	)
	(footprint "antmicro-footprints:R_0402_1005Metric"
		(layer "F.Cu")
		(at 116.4 107.1)
		(descr "Resistor SMD 0402")
		(tags "resistor SMD 0402")
		(property "Reference" "R22"
			(at 0 -8.1 0)
			(layer "F.SilkS")
			(effects
				(font
					(size 0.7 0.7)
					(thickness 0.15)
				)
			)
		)
		(property "Value" "R_8k87_0402"
			(at -1.011843 1.772047 0)
			(layer "F.Fab")
			(effects
				(font
					(size 0.7 0.7)
					(thickness 0.15)
				)
				(justify left bottom)
			)
		)
		(property "Datasheet" "https://www.bourns.com/docs/product-datasheets/cr.pdf"
			(at 0 0 0)
			(layer "F.Fab")
			(hide yes)
			(effects
				(font
					(size 1.27 1.27)
					(thickness 0.15)
				)
			)
		)
		(property "Description" "SMD Chip Resistor, 8.87 kohm, ± 1%, 100 mW, 0402 [1005 Metric], Thick Film, Precision"
			(at 0 0 0)
			(layer "F.Fab")
			(hide yes)
			(effects
				(font
					(size 1.27 1.27)
					(thickness 0.15)
				)
			)
		)
		(property "MPN" "CR0402-FX-8871GLF"
			(at 0 0 0)
			(unlocked yes)
			(layer "F.Fab")
			(hide yes)
			(effects
				(font
					(size 1 1)
					(thickness 0.15)
				)
			)
		)
		(property "Manufacturer" "Bourns"
			(at 0 0 0)
			(unlocked yes)
			(layer "F.Fab")
			(hide yes)
			(effects
				(font
					(size 1 1)
					(thickness 0.15)
				)
			)
		)
		(property "License" "Apache-2.0"
			(at 0 0 0)
			(unlocked yes)
			(layer "F.Fab")
			(hide yes)
			(effects
				(font
					(size 1 1)
					(thickness 0.15)
				)
			)
		)
		(property "Val" "8k87"
			(at 0 0 0)
			(unlocked yes)
			(layer "F.Fab")
			(hide yes)
			(effects
				(font
					(size 1 1)
					(thickness 0.15)
				)
			)
		)
		(property "Tolerance" "1%"
			(at 0 0 0)
			(unlocked yes)
			(layer "F.Fab")
			(hide yes)
			(effects
				(font
					(size 1 1)
					(thickness 0.15)
				)
			)
		)
		(property "Author" "Antmicro"
			(at 0 0 0)
			(unlocked yes)
			(layer "F.Fab")
			(hide yes)
			(effects
				(font
					(size 1 1)
					(thickness 0.15)
				)
			)
		)
		(sheetname "/PD and TB DC-DC/")
		(sheetfile "PD_and_TB_DC_DC.kicad_sch")
		(attr smd)
		(fp_rect
			(start -0.925 -0.47)
			(end 0.925 0.47)
			(stroke
				(width 0.05)
				(type default)
			)
			(fill no)
			(layer "F.CrtYd")
		)
		(fp_rect
			(start -0.5 -0.25)
			(end 0.5 0.25)
			(stroke
				(width 0.15)
				(type solid)
			)
			(fill no)
			(layer "F.Fab")
		)
		(fp_text user "License: Apache-2.0"
			(at -0.95 5.169 0)
			(layer "F.Fab")
			(effects
				(font
					(size 0.7 0.7)
					(thickness 0.15)
				)
				(justify left bottom)
			)
		)
		(fp_text user "Author: Antmicro"
			(at -0.95 4.169 0)
			(layer "F.Fab")
			(effects
				(font
					(size 0.7 0.7)
					(thickness 0.15)
				)
				(justify left bottom)
			)
		)
		(fp_text user "${REFERENCE}"
			(at -0.95 3.168 0)
			(layer "F.Fab")
			(effects
				(font
					(size 0.7 0.7)
					(thickness 0.15)
				)
				(justify left bottom)
			)
		)
		(pad "1" smd roundrect
			(at -0.48 0)
			(size 0.59 0.64)
			(layers "F.Cu" "F.Mask" "F.Paste")
			(roundrect_rratio 0.25)
			(net 23 "GND")
			(pintype "passive")
		)
		(pad "2" smd roundrect
			(at 0.48 0)
			(size 0.59 0.64)
			(layers "F.Cu" "F.Mask" "F.Paste")
			(roundrect_rratio 0.25)
			(net 166 "Net-(U2-FB)")
			(pintype "passive")
		)
	)
	(footprint "antmicro-footprints:R_0402_1005Metric"
		(layer "F.Cu")
		(at 142.31 95.674999 180)
		(descr "Resistor SMD 0402")
		(tags "resistor SMD 0402")
		(property "Reference" "R178"
			(at -2.190001 -0.025001 180)
			(layer "F.SilkS")
			(effects
				(font
					(size 0.7 0.7)
					(thickness 0.15)
				)
			)
		)
		(property "Value" "R_22R_0402"
			(at -1.011843 1.772047 180)
			(layer "F.Fab")
			(effects
				(font
					(size 0.7 0.7)
					(thickness 0.15)
				)
				(justify left bottom)
			)
		)
		(property "Datasheet" "https://www.bourns.com/docs/product-datasheets/cr.pdf"
			(at 0 0 180)
			(layer "F.Fab")
			(hide yes)
			(effects
				(font
					(size 1.27 1.27)
					(thickness 0.15)
				)
			)
		)
		(property "Description" "SMD Chip Resistor, 22 ohm, ± 1%, 62.5 mW, 0402 [1005 Metric], Thick Film, General Purpose"
			(at 0 0 180)
			(layer "F.Fab")
			(hide yes)
			(effects
				(font
					(size 1.27 1.27)
					(thickness 0.15)
				)
			)
		)
		(property "MPN" "CR0402-FX-22R0GLF"
			(at 0 0 180)
			(unlocked yes)
			(layer "F.Fab")
			(hide yes)
			(effects
				(font
					(size 1 1)
					(thickness 0.15)
				)
			)
		)
		(property "Manufacturer" "Bourns"
			(at 0 0 180)
			(unlocked yes)
			(layer "F.Fab")
			(hide yes)
			(effects
				(font
					(size 1 1)
					(thickness 0.15)
				)
			)
		)
		(property "License" "Apache-2.0"
			(at 0 0 180)
			(unlocked yes)
			(layer "F.Fab")
			(hide yes)
			(effects
				(font
					(size 1 1)
					(thickness 0.15)
				)
			)
		)
		(property "Author" "Antmicro"
			(at 0 0 180)
			(unlocked yes)
			(layer "F.Fab")
			(hide yes)
			(effects
				(font
					(size 1 1)
					(thickness 0.15)
				)
			)
		)
		(property "Val" "22R"
			(at 0 0 180)
			(unlocked yes)
			(layer "F.Fab")
			(hide yes)
			(effects
				(font
					(size 1 1)
					(thickness 0.15)
				)
			)
		)
		(property "Tolerance" "1%"
			(at 0 0 180)
			(unlocked yes)
			(layer "F.Fab")
			(hide yes)
			(effects
				(font
					(size 1 1)
					(thickness 0.15)
				)
			)
		)
		(sheetname "/X710-AT2 Misc/")
		(sheetfile "x710-at2-mics.kicad_sch")
		(attr smd)
		(fp_rect
			(start -0.925 -0.47)
			(end 0.925 0.47)
			(stroke
				(width 0.05)
				(type default)
			)
			(fill no)
			(layer "F.CrtYd")
		)
		(fp_rect
			(start -0.5 -0.25)
			(end 0.5 0.25)
			(stroke
				(width 0.15)
				(type solid)
			)
			(fill no)
			(layer "F.Fab")
		)
		(fp_text user "License: Apache-2.0"
			(at -0.95 5.169 180)
			(layer "F.Fab")
			(effects
				(font
					(size 0.7 0.7)
					(thickness 0.15)
				)
				(justify left bottom)
			)
		)
		(fp_text user "Author: Antmicro"
			(at -0.95 4.169 180)
			(layer "F.Fab")
			(effects
				(font
					(size 0.7 0.7)
					(thickness 0.15)
				)
				(justify left bottom)
			)
		)
		(fp_text user "${REFERENCE}"
			(at -0.95 3.168 180)
			(layer "F.Fab")
			(effects
				(font
					(size 0.7 0.7)
					(thickness 0.15)
				)
				(justify left bottom)
			)
		)
		(pad "1" smd roundrect
			(at -0.48 0 180)
			(size 0.59 0.64)
			(layers "F.Cu" "F.Mask" "F.Paste")
			(roundrect_rratio 0.25)
			(net 81 "/X710-AT2 Misc/FLSH_SCK")
			(pintype "passive")
		)
		(pad "2" smd roundrect
			(at 0.48 0 180)
			(size 0.59 0.64)
			(layers "F.Cu" "F.Mask" "F.Paste")
			(roundrect_rratio 0.25)
			(net 353 "/X710 flash memory/FLASH.CLK")
			(pintype "passive")
		)
	)
	(footprint "antmicro-footprints:MP_Pad6mm_Drill3.2mm"
		(layer "F.Cu")
		(at 180 50)
		(property "Reference" "MP3"
			(at -1 -3.6 0)
			(layer "F.SilkS")
			(effects
				(font
					(size 0.7 0.7)
					(thickness 0.15)
				)
				(justify left bottom)
			)
		)
		(property "Value" "MP_Pad6mm_Drill3.2mm"
			(at 0 3.9 0)
			(layer "F.Fab")
			(effects
				(font
					(size 0.7 0.7)
					(thickness 0.15)
				)
				(justify left bottom)
			)
		)
		(property "Description" "Mechanical part"
			(at 0 0 0)
			(layer "F.Fab")
			(hide yes)
			(effects
				(font
					(size 1.27 1.27)
					(thickness 0.15)
				)
			)
		)
		(property "Author" "Antmicro"
			(at 0 0 0)
			(unlocked yes)
			(layer "F.Fab")
			(hide yes)
			(effects
				(font
					(size 1 1)
					(thickness 0.15)
				)
			)
		)
		(property "License" "Apache-2.0"
			(at 0 0 0)
			(unlocked yes)
			(layer "F.Fab")
			(hide yes)
			(effects
				(font
					(size 1 1)
					(thickness 0.15)
				)
			)
		)
		(sheetname "/")
		(sheetfile "thunderbolt-to-10gbe-adapter.kicad_sch")
		(attr exclude_from_pos_files exclude_from_bom)
		(fp_circle
			(center 0 0)
			(end 3.25 0)
			(stroke
				(width 0.05)
				(type default)
			)
			(fill no)
			(layer "F.CrtYd")
		)
		(fp_text user "License: Apache-2.0"
			(at -0.178 8.425 0)
			(layer "F.Fab")
			(effects
				(font
					(size 0.7 0.7)
					(thickness 0.15)
				)
				(justify left bottom)
			)
		)
		(fp_text user "Author: Antmicro"
			(at -0.178 7.225 0)
			(layer "F.Fab")
			(effects
				(font
					(size 0.7 0.7)
					(thickness 0.15)
				)
				(justify left bottom)
			)
		)
		(fp_text user "${REFERENCE}"
			(at -0.178 6.025 0)
			(layer "F.Fab")
			(effects
				(font
					(size 0.7 0.7)
					(thickness 0.15)
				)
				(justify left bottom)
			)
		)
		(pad "1" thru_hole circle
			(at 0 0)
			(size 6 6)
			(drill 3.2)
			(layers "*.Cu" "*.Mask")
			(remove_unused_layers no)
			(net 23 "GND")
			(pintype "passive")
		)
	)
)
